(kicad_pcb
	(version 20241229)
	(generator "pcbnew")
	(generator_version "9.0")
	(general
		(thickness 1.61)
		(legacy_teardrops no)
	)
	(paper "A3")
	(title_block
		(title "SO-DIMM DDR5 Tester")
		(date "2025-11-26")
		(rev "1.3.0")
		(comment 9 "footprints 33-38 of 627")
	)
	(layers
		(0 "F.Cu" signal)
		(4 "In1.Cu" power)
		(6 "In2.Cu" mixed)
		(8 "In3.Cu" power)
		(10 "In4.Cu" mixed)
		(12 "In5.Cu" power)
		(14 "In6.Cu" mixed)
		(16 "In7.Cu" power)
		(18 "In8.Cu" power)
		(20 "In9.Cu" mixed)
		(22 "In10.Cu" power)
		(2 "B.Cu" signal)
		(9 "F.Adhes" user "F.Adhesive")
		(11 "B.Adhes" user "B.Adhesive")
		(13 "F.Paste" user)
		(15 "B.Paste" user)
		(5 "F.SilkS" user "F.Silkscreen")
		(7 "B.SilkS" user "B.Silkscreen")
		(1 "F.Mask" user)
		(3 "B.Mask" user)
		(17 "Dwgs.User" user "User.Drawings")
		(19 "Cmts.User" user "User.Comments")
		(21 "Eco1.User" user "User.Eco1")
		(23 "Eco2.User" user "User.Eco2")
		(25 "Edge.Cuts" user)
		(27 "Margin" user)
		(31 "F.CrtYd" user "F.Courtyard")
		(29 "B.CrtYd" user "B.Courtyard")
		(35 "F.Fab" user)
		(33 "B.Fab" user)
	)
	(footprint "antmicro-footprints:C_0402_1005Metric"
		(layer "F.Cu")
		(at 102.600501 156.458851 90)
		(descr "Capacitor SMD 0402")
		(tags "capacitor SMD 0402")
		(property "Reference" "C154"
			(at 0 -0.699 90)
			(layer "F.SilkS")
			(hide yes)
			(effects
				(font
					(size 0.7 0.7)
					(thickness 0.15)
				)
				(justify left bottom)
			)
		)
		(property "Value" "C_10n_0402"
			(at -1.022927 2.155213 90)
			(layer "F.Fab")
			(effects
				(font
					(size 0.7 0.7)
					(thickness 0.15)
				)
				(justify left bottom)
			)
		)
		(property "Datasheet" "https://www.murata.com/products/productdetail?partno=GRM155R71H103KA88%23"
			(at 0 0 90)
			(layer "F.Fab")
			(hide yes)
			(effects
				(font
					(size 1.27 1.27)
					(thickness 0.15)
				)
			)
		)
		(property "Author" "Antmicro"
			(at 259.059352 53.85835 0)
			(layer "F.Fab")
			(hide yes)
			(effects
				(font
					(size 1 1)
					(thickness 0.15)
				)
			)
		)
		(property "Dielectric" "X7R"
			(at 259.059352 53.85835 0)
			(layer "F.Fab")
			(hide yes)
			(effects
				(font
					(size 1 1)
					(thickness 0.15)
				)
			)
		)
		(property "License" "Apache-2.0"
			(at 259.059352 53.85835 0)
			(layer "F.Fab")
			(hide yes)
			(effects
				(font
					(size 1 1)
					(thickness 0.15)
				)
			)
		)
		(property "MPN" "GRM155R71H103KA88D"
			(at 259.059352 53.85835 0)
			(layer "F.Fab")
			(hide yes)
			(effects
				(font
					(size 1 1)
					(thickness 0.15)
				)
			)
		)
		(property "Manufacturer" "Murata"
			(at 259.059352 53.85835 0)
			(layer "F.Fab")
			(hide yes)
			(effects
				(font
					(size 1 1)
					(thickness 0.15)
				)
			)
		)
		(property "Val" "10n"
			(at 259.059352 53.85835 0)
			(layer "F.Fab")
			(hide yes)
			(effects
				(font
					(size 1 1)
					(thickness 0.15)
				)
			)
		)
		(property "Voltage" "50V"
			(at 259.059352 53.85835 0)
			(layer "F.Fab")
			(hide yes)
			(effects
				(font
					(size 1 1)
					(thickness 0.15)
				)
			)
		)
		(sheetname "/Ethernet/")
		(sheetfile "ethernet.kicad_sch")
		(attr smd)
		(fp_rect
			(start -0.9659 -0.481258)
			(end 0.9649 0.458742)
			(stroke
				(width 0.05)
				(type solid)
			)
			(fill no)
			(layer "F.CrtYd")
		)
		(fp_line
			(start 0.499 -0.25)
			(end 0.499 0.248)
			(stroke
				(width 0.15)
				(type solid)
			)
			(layer "F.Fab")
		)
		(fp_line
			(start -0.499 -0.25)
			(end 0.499 -0.25)
			(stroke
				(width 0.15)
				(type solid)
			)
			(layer "F.Fab")
		)
		(fp_line
			(start 0.499 0.248)
			(end -0.499 0.248)
			(stroke
				(width 0.15)
				(type solid)
			)
			(layer "F.Fab")
		)
		(fp_line
			(start -0.499 0.248)
			(end -0.499 -0.25)
			(stroke
				(width 0.15)
				(type solid)
			)
			(layer "F.Fab")
		)
		(pad "1" smd roundrect
			(at -0.484 0 90)
			(size 0.59 0.64)
			(layers "F.Cu" "F.Mask" "F.Paste")
			(roundrect_rratio 0.25)
			(net 1 "GND")
			(pintype "passive")
		)
		(pad "2" smd roundrect
			(at 0.484 0 90)
			(size 0.59 0.64)
			(layers "F.Cu" "F.Mask" "F.Paste")
			(roundrect_rratio 0.25)
			(net 133 "/Ethernet/AVDDL_PLL")
			(pintype "passive")
		)
	)
	(footprint "antmicro-footprints:C_0402_1005Metric"
		(layer "F.Cu")
		(at 87.400501 157.458851 -90)
		(descr "Capacitor SMD 0402")
		(tags "capacitor SMD 0402")
		(property "Reference" "C150"
			(at 0 -0.699 270)
			(layer "F.SilkS")
			(hide yes)
			(effects
				(font
					(size 0.7 0.7)
					(thickness 0.15)
				)
				(justify left bottom)
			)
		)
		(property "Value" "C_10n_0402"
			(at -1.022927 2.155213 270)
			(layer "F.Fab")
			(effects
				(font
					(size 0.7 0.7)
					(thickness 0.15)
				)
				(justify left bottom)
			)
		)
		(property "Datasheet" "https://www.murata.com/products/productdetail?partno=GRM155R71H103KA88%23"
			(at 0 0 270)
			(layer "F.Fab")
			(hide yes)
			(effects
				(font
					(size 1.27 1.27)
					(thickness 0.15)
				)
			)
		)
		(property "Author" "Antmicro"
			(at -70.05835 244.859352 0)
			(layer "F.Fab")
			(hide yes)
			(effects
				(font
					(size 1 1)
					(thickness 0.15)
				)
			)
		)
		(property "Dielectric" "X7R"
			(at -70.05835 244.859352 0)
			(layer "F.Fab")
			(hide yes)
			(effects
				(font
					(size 1 1)
					(thickness 0.15)
				)
			)
		)
		(property "License" "Apache-2.0"
			(at -70.05835 244.859352 0)
			(layer "F.Fab")
			(hide yes)
			(effects
				(font
					(size 1 1)
					(thickness 0.15)
				)
			)
		)
		(property "MPN" "GRM155R71H103KA88D"
			(at -70.05835 244.859352 0)
			(layer "F.Fab")
			(hide yes)
			(effects
				(font
					(size 1 1)
					(thickness 0.15)
				)
			)
		)
		(property "Manufacturer" "Murata"
			(at -70.05835 244.859352 0)
			(layer "F.Fab")
			(hide yes)
			(effects
				(font
					(size 1 1)
					(thickness 0.15)
				)
			)
		)
		(property "Val" "10n"
			(at -70.05835 244.859352 0)
			(layer "F.Fab")
			(hide yes)
			(effects
				(font
					(size 1 1)
					(thickness 0.15)
				)
			)
		)
		(property "Voltage" "50V"
			(at -70.05835 244.859352 0)
			(layer "F.Fab")
			(hide yes)
			(effects
				(font
					(size 1 1)
					(thickness 0.15)
				)
			)
		)
		(sheetname "/Ethernet/")
		(sheetfile "ethernet.kicad_sch")
		(attr smd)
		(fp_rect
			(start -0.9659 -0.481258)
			(end 0.9649 0.458742)
			(stroke
				(width 0.05)
				(type solid)
			)
			(fill no)
			(layer "F.CrtYd")
		)
		(fp_line
			(start -0.499 0.248)
			(end -0.499 -0.25)
			(stroke
				(width 0.15)
				(type solid)
			)
			(layer "F.Fab")
		)
		(fp_line
			(start 0.499 0.248)
			(end -0.499 0.248)
			(stroke
				(width 0.15)
				(type solid)
			)
			(layer "F.Fab")
		)
		(fp_line
			(start -0.499 -0.25)
			(end 0.499 -0.25)
			(stroke
				(width 0.15)
				(type solid)
			)
			(layer "F.Fab")
		)
		(fp_line
			(start 0.499 -0.25)
			(end 0.499 0.248)
			(stroke
				(width 0.15)
				(type solid)
			)
			(layer "F.Fab")
		)
		(pad "1" smd roundrect
			(at -0.484 0 270)
			(size 0.59 0.64)
			(layers "F.Cu" "F.Mask" "F.Paste")
			(roundrect_rratio 0.25)
			(net 199 "+1V2")
			(pintype "passive")
		)
		(pad "2" smd roundrect
			(at 0.484 0 270)
			(size 0.59 0.64)
			(layers "F.Cu" "F.Mask" "F.Paste")
			(roundrect_rratio 0.25)
			(net 1 "GND")
			(pintype "passive")
		)
	)
	(footprint "antmicro-footprints:C_0402_1005Metric"
		(layer "F.Cu")
		(at 87.400501 154.058851 -90)
		(descr "Capacitor SMD 0402")
		(tags "capacitor SMD 0402")
		(property "Reference" "C147"
			(at 0 -0.699 270)
			(layer "F.SilkS")
			(hide yes)
			(effects
				(font
					(size 0.7 0.7)
					(thickness 0.15)
				)
				(justify left bottom)
			)
		)
		(property "Value" "C_10n_0402"
			(at -1.022927 2.155213 270)
			(layer "F.Fab")
			(effects
				(font
					(size 0.7 0.7)
					(thickness 0.15)
				)
				(justify left bottom)
			)
		)
		(property "Datasheet" "https://www.murata.com/products/productdetail?partno=GRM155R71H103KA88%23"
			(at 0 0 270)
			(layer "F.Fab")
			(hide yes)
			(effects
				(font
					(size 1.27 1.27)
					(thickness 0.15)
				)
			)
		)
		(property "Author" "Antmicro"
			(at -66.65835 241.459352 0)
			(layer "F.Fab")
			(hide yes)
			(effects
				(font
					(size 1 1)
					(thickness 0.15)
				)
			)
		)
		(property "Dielectric" "X7R"
			(at -66.65835 241.459352 0)
			(layer "F.Fab")
			(hide yes)
			(effects
				(font
					(size 1 1)
					(thickness 0.15)
				)
			)
		)
		(property "License" "Apache-2.0"
			(at -66.65835 241.459352 0)
			(layer "F.Fab")
			(hide yes)
			(effects
				(font
					(size 1 1)
					(thickness 0.15)
				)
			)
		)
		(property "MPN" "GRM155R71H103KA88D"
			(at -66.65835 241.459352 0)
			(layer "F.Fab")
			(hide yes)
			(effects
				(font
					(size 1 1)
					(thickness 0.15)
				)
			)
		)
		(property "Manufacturer" "Murata"
			(at -66.65835 241.459352 0)
			(layer "F.Fab")
			(hide yes)
			(effects
				(font
					(size 1 1)
					(thickness 0.15)
				)
			)
		)
		(property "Val" "10n"
			(at -66.65835 241.459352 0)
			(layer "F.Fab")
			(hide yes)
			(effects
				(font
					(size 1 1)
					(thickness 0.15)
				)
			)
		)
		(property "Voltage" "50V"
			(at -66.65835 241.459352 0)
			(layer "F.Fab")
			(hide yes)
			(effects
				(font
					(size 1 1)
					(thickness 0.15)
				)
			)
		)
		(sheetname "/Ethernet/")
		(sheetfile "ethernet.kicad_sch")
		(attr smd)
		(fp_rect
			(start -0.9659 -0.481258)
			(end 0.9649 0.458742)
			(stroke
				(width 0.05)
				(type solid)
			)
			(fill no)
			(layer "F.CrtYd")
		)
		(fp_line
			(start -0.499 0.248)
			(end -0.499 -0.25)
			(stroke
				(width 0.15)
				(type solid)
			)
			(layer "F.Fab")
		)
		(fp_line
			(start 0.499 0.248)
			(end -0.499 0.248)
			(stroke
				(width 0.15)
				(type solid)
			)
			(layer "F.Fab")
		)
		(fp_line
			(start -0.499 -0.25)
			(end 0.499 -0.25)
			(stroke
				(width 0.15)
				(type solid)
			)
			(layer "F.Fab")
		)
		(fp_line
			(start 0.499 -0.25)
			(end 0.499 0.248)
			(stroke
				(width 0.15)
				(type solid)
			)
			(layer "F.Fab")
		)
		(pad "1" smd roundrect
			(at -0.484 0 270)
			(size 0.59 0.64)
			(layers "F.Cu" "F.Mask" "F.Paste")
			(roundrect_rratio 0.25)
			(net 200 "+3V3")
			(pintype "passive")
		)
		(pad "2" smd roundrect
			(at 0.484 0 270)
			(size 0.59 0.64)
			(layers "F.Cu" "F.Mask" "F.Paste")
			(roundrect_rratio 0.25)
			(net 1 "GND")
			(pintype "passive")
		)
	)
	(footprint "antmicro-footprints:C_0402_1005Metric"
		(layer "F.Cu")
		(at 87.400501 151.733157 90)
		(descr "Capacitor SMD 0402")
		(tags "capacitor SMD 0402")
		(property "Reference" "C156"
			(at 0 -0.699 90)
			(layer "F.SilkS")
			(hide yes)
			(effects
				(font
					(size 0.7 0.7)
					(thickness 0.15)
				)
				(justify left bottom)
			)
		)
		(property "Value" "C_10n_0402"
			(at -1.022927 2.155213 90)
			(layer "F.Fab")
			(effects
				(font
					(size 0.7 0.7)
					(thickness 0.15)
				)
				(justify left bottom)
			)
		)
		(property "Datasheet" "https://www.murata.com/products/productdetail?partno=GRM155R71H103KA88%23"
			(at 0 0 90)
			(layer "F.Fab")
			(hide yes)
			(effects
				(font
					(size 1.27 1.27)
					(thickness 0.15)
				)
			)
		)
		(property "Author" "Antmicro"
			(at 239.133658 64.332656 0)
			(layer "F.Fab")
			(hide yes)
			(effects
				(font
					(size 1 1)
					(thickness 0.15)
				)
			)
		)
		(property "Dielectric" "X7R"
			(at 239.133658 64.332656 0)
			(layer "F.Fab")
			(hide yes)
			(effects
				(font
					(size 1 1)
					(thickness 0.15)
				)
			)
		)
		(property "License" "Apache-2.0"
			(at 239.133658 64.332656 0)
			(layer "F.Fab")
			(hide yes)
			(effects
				(font
					(size 1 1)
					(thickness 0.15)
				)
			)
		)
		(property "MPN" "GRM155R71H103KA88D"
			(at 239.133658 64.332656 0)
			(layer "F.Fab")
			(hide yes)
			(effects
				(font
					(size 1 1)
					(thickness 0.15)
				)
			)
		)
		(property "Manufacturer" "Murata"
			(at 239.133658 64.332656 0)
			(layer "F.Fab")
			(hide yes)
			(effects
				(font
					(size 1 1)
					(thickness 0.15)
				)
			)
		)
		(property "Val" "10n"
			(at 239.133658 64.332656 0)
			(layer "F.Fab")
			(hide yes)
			(effects
				(font
					(size 1 1)
					(thickness 0.15)
				)
			)
		)
		(property "Voltage" "50V"
			(at 239.133658 64.332656 0)
			(layer "F.Fab")
			(hide yes)
			(effects
				(font
					(size 1 1)
					(thickness 0.15)
				)
			)
		)
		(sheetname "/Ethernet/")
		(sheetfile "ethernet.kicad_sch")
		(attr smd)
		(fp_rect
			(start -0.9659 -0.481258)
			(end 0.9649 0.458742)
			(stroke
				(width 0.05)
				(type solid)
			)
			(fill no)
			(layer "F.CrtYd")
		)
		(fp_line
			(start 0.499 -0.25)
			(end 0.499 0.248)
			(stroke
				(width 0.15)
				(type solid)
			)
			(layer "F.Fab")
		)
		(fp_line
			(start -0.499 -0.25)
			(end 0.499 -0.25)
			(stroke
				(width 0.15)
				(type solid)
			)
			(layer "F.Fab")
		)
		(fp_line
			(start 0.499 0.248)
			(end -0.499 0.248)
			(stroke
				(width 0.15)
				(type solid)
			)
			(layer "F.Fab")
		)
		(fp_line
			(start -0.499 0.248)
			(end -0.499 -0.25)
			(stroke
				(width 0.15)
				(type solid)
			)
			(layer "F.Fab")
		)
		(pad "1" smd roundrect
			(at -0.484 0 90)
			(size 0.59 0.64)
			(layers "F.Cu" "F.Mask" "F.Paste")
			(roundrect_rratio 0.25)
			(net 199 "+1V2")
			(pintype "passive")
		)
		(pad "2" smd roundrect
			(at 0.484 0 90)
			(size 0.59 0.64)
			(layers "F.Cu" "F.Mask" "F.Paste")
			(roundrect_rratio 0.25)
			(net 1 "GND")
			(pintype "passive")
		)
	)
	(footprint "antmicro-footprints:C_0402_1005Metric"
		(layer "F.Cu")
		(at 102.800501 154.958851 180)
		(descr "Capacitor SMD 0402")
		(tags "capacitor SMD 0402")
		(property "Reference" "C163"
			(at 0 -0.699 180)
			(layer "F.SilkS")
			(hide yes)
			(effects
				(font
					(size 0.7 0.7)
					(thickness 0.15)
				)
				(justify left bottom)
			)
		)
		(property "Value" "C_18p_0402"
			(at -1.022927 2.155213 180)
			(layer "F.Fab")
			(effects
				(font
					(size 0.7 0.7)
					(thickness 0.15)
				)
				(justify left bottom)
			)
		)
		(property "Datasheet" "https://product.samsungsem.com/mlcc/CL05C180JB51PN.do"
			(at 0 0 180)
			(layer "F.Fab")
			(hide yes)
			(effects
				(font
					(size 1.27 1.27)
					(thickness 0.15)
				)
			)
		)
		(property "Author" "Antmicro"
			(at 205.601002 309.917702 0)
			(layer "F.Fab")
			(hide yes)
			(effects
				(font
					(size 1 1)
					(thickness 0.15)
				)
			)
		)
		(property "Dielectric" ""
			(at 205.601002 309.917702 0)
			(layer "F.Fab")
			(hide yes)
			(effects
				(font
					(size 1 1)
					(thickness 0.15)
				)
			)
		)
		(property "License" "Apache-2.0"
			(at 205.601002 309.917702 0)
			(layer "F.Fab")
			(hide yes)
			(effects
				(font
					(size 1 1)
					(thickness 0.15)
				)
			)
		)
		(property "MPN" "CL05C180JB51PNC"
			(at 205.601002 309.917702 0)
			(layer "F.Fab")
			(hide yes)
			(effects
				(font
					(size 1 1)
					(thickness 0.15)
				)
			)
		)
		(property "Manufacturer" "Samsung Electro-Mechanics"
			(at 205.601002 309.917702 0)
			(layer "F.Fab")
			(hide yes)
			(effects
				(font
					(size 1 1)
					(thickness 0.15)
				)
			)
		)
		(property "Val" "18p"
			(at 205.601002 309.917702 0)
			(layer "F.Fab")
			(hide yes)
			(effects
				(font
					(size 1 1)
					(thickness 0.15)
				)
			)
		)
		(property "Voltage" ""
			(at 205.601002 309.917702 0)
			(layer "F.Fab")
			(hide yes)
			(effects
				(font
					(size 1 1)
					(thickness 0.15)
				)
			)
		)
		(sheetname "/Ethernet/")
		(sheetfile "ethernet.kicad_sch")
		(attr smd)
		(fp_rect
			(start -0.9659 -0.481258)
			(end 0.9649 0.458742)
			(stroke
				(width 0.05)
				(type solid)
			)
			(fill no)
			(layer "F.CrtYd")
		)
		(fp_line
			(start 0.499 0.248)
			(end -0.499 0.248)
			(stroke
				(width 0.15)
				(type solid)
			)
			(layer "F.Fab")
		)
		(fp_line
			(start 0.499 -0.25)
			(end 0.499 0.248)
			(stroke
				(width 0.15)
				(type solid)
			)
			(layer "F.Fab")
		)
		(fp_line
			(start -0.499 0.248)
			(end -0.499 -0.25)
			(stroke
				(width 0.15)
				(type solid)
			)
			(layer "F.Fab")
		)
		(fp_line
			(start -0.499 -0.25)
			(end 0.499 -0.25)
			(stroke
				(width 0.15)
				(type solid)
			)
			(layer "F.Fab")
		)
		(pad "1" smd roundrect
			(at -0.484 0 180)
			(size 0.59 0.64)
			(layers "F.Cu" "F.Mask" "F.Paste")
			(roundrect_rratio 0.25)
			(net 1 "GND")
			(pintype "passive")
		)
		(pad "2" smd roundrect
			(at 0.484 0 180)
			(size 0.59 0.64)
			(layers "F.Cu" "F.Mask" "F.Paste")
			(roundrect_rratio 0.25)
			(net 300 "Net-(U15-XO)")
			(pintype "passive")
		)
	)
	(footprint "antmicro-footprints:C_0402_1005Metric"
		(layer "F.Cu")
		(at 104.000501 150.158851)
		(descr "Capacitor SMD 0402")
		(tags "capacitor SMD 0402")
		(property "Reference" "C162"
			(at 0 -0.699 0)
			(layer "F.SilkS")
			(hide yes)
			(effects
				(font
					(size 0.7 0.7)
					(thickness 0.15)
				)
				(justify left bottom)
			)
		)
		(property "Value" "C_18p_0402"
			(at -1.022927 2.155213 0)
			(layer "F.Fab")
			(effects
				(font
					(size 0.7 0.7)
					(thickness 0.15)
				)
				(justify left bottom)
			)
		)
		(property "Datasheet" "https://product.samsungsem.com/mlcc/CL05C180JB51PN.do"
			(at 0 0 0)
			(layer "F.Fab")
			(hide yes)
			(effects
				(font
					(size 1.27 1.27)
					(thickness 0.15)
				)
			)
		)
		(property "Author" "Antmicro"
			(at 0 0 0)
			(layer "F.Fab")
			(hide yes)
			(effects
				(font
					(size 1 1)
					(thickness 0.15)
				)
			)
		)
		(property "Dielectric" ""
			(at 0 0 0)
			(layer "F.Fab")
			(hide yes)
			(effects
				(font
					(size 1 1)
					(thickness 0.15)
				)
			)
		)
		(property "License" "Apache-2.0"
			(at 0 0 0)
			(layer "F.Fab")
			(hide yes)
			(effects
				(font
					(size 1 1)
					(thickness 0.15)
				)
			)
		)
		(property "MPN" "CL05C180JB51PNC"
			(at 0 0 0)
			(layer "F.Fab")
			(hide yes)
			(effects
				(font
					(size 1 1)
					(thickness 0.15)
				)
			)
		)
		(property "Manufacturer" "Samsung Electro-Mechanics"
			(at 0 0 0)
			(layer "F.Fab")
			(hide yes)
			(effects
				(font
					(size 1 1)
					(thickness 0.15)
				)
			)
		)
		(property "Val" "18p"
			(at 0 0 0)
			(layer "F.Fab")
			(hide yes)
			(effects
				(font
					(size 1 1)
					(thickness 0.15)
				)
			)
		)
		(property "Voltage" ""
			(at 0 0 0)
			(layer "F.Fab")
			(hide yes)
			(effects
				(font
					(size 1 1)
					(thickness 0.15)
				)
			)
		)
		(sheetname "/Ethernet/")
		(sheetfile "ethernet.kicad_sch")
		(attr smd)
		(fp_rect
			(start -0.9659 -0.481258)
			(end 0.9649 0.458742)
			(stroke
				(width 0.05)
				(type solid)
			)
			(fill no)
			(layer "F.CrtYd")
		)
		(fp_line
			(start -0.499 -0.25)
			(end 0.499 -0.25)
			(stroke
				(width 0.15)
				(type solid)
			)
			(layer "F.Fab")
		)
		(fp_line
			(start -0.499 0.248)
			(end -0.499 -0.25)
			(stroke
				(width 0.15)
				(type solid)
			)
			(layer "F.Fab")
		)
		(fp_line
			(start 0.499 -0.25)
			(end 0.499 0.248)
			(stroke
				(width 0.15)
				(type solid)
			)
			(layer "F.Fab")
		)
		(fp_line
			(start 0.499 0.248)
			(end -0.499 0.248)
			(stroke
				(width 0.15)
				(type solid)
			)
			(layer "F.Fab")
		)
		(pad "1" smd roundrect
			(at -0.484 0)
			(size 0.59 0.64)
			(layers "F.Cu" "F.Mask" "F.Paste")
			(roundrect_rratio 0.25)
			(net 1 "GND")
			(pintype "passive")
		)
		(pad "2" smd roundrect
			(at 0.484 0)
			(size 0.59 0.64)
			(layers "F.Cu" "F.Mask" "F.Paste")
			(roundrect_rratio 0.25)
			(net 299 "Net-(U15-XI)")
			(pintype "passive")
		)
	)
)
